FILE_TYPE = MULTI_PHYS_TABLE;

PART '74LVC1G07GV'

{========================================================================================}
:VALUE         | PART_TYPE | MATERIAL | PART_NUMBER       = STANDARD | LIFECYCLE      | PART_NUMBER       | JEDEC_TYPE       | DESCRIPTION                              | MANUFTR | MANUF_PN      | RD_CMPLS_LVL | CMPLS_LVL | FROM_PJ    | CLASS | DIP_SMD | DATA                  | EE_CHECK_LIST | FP_ECN            | PSL | CREATOR | STATUS | MSD       | ESD_CDM | ESD_HBM | ESD_MM | PIN_LENGTH_SHORT_PIN | PIN_LENGTH_LONG_PIN | CREATEDAY  ;
{========================================================================================}
 '74LVC1G07GV' | 'SMLF'    | 'IC'     | 'AL1G0007001'(!)  = ''       | ''             | 'AL1G0007001'     |'SC-74A_2-9X1-5'| 'IC OTHER(5P) 74LVC1G07GV(SOT753)'       | 'NXP'   | '74LVC1G07GV' | 'EP(V1)'     | 'EP(V1)'  | 'S3D-ALAN' | 'IC'  | ''      | 'NXP_74LVC1G07GV.pdf' | ''            | '74LVC1G07GV.msg' | ''  | ''      | ''     | 'Level-1' | 'NA'    | '2000V' | '200V' | '0 MILS'             | '0 MILS'            | '20191122'
 '74LVC1G07GV' | 'SMLF'    | 'EMPTY'  | 'AL1G0007001'(!)  = ''       | ''             | 'AL1G0007001'     |'SC-74A_2-9X1-5'| 'IC OTHER(5P) 74LVC1G07GV(SOT753)'       | 'NXP'   | '74LVC1G07GV' | 'EP(V1)'     | 'EP(V1)'  | 'S3D-ALAN' | 'IC'  | ''      | 'NXP_74LVC1G07GV.pdf' | ''            | '74LVC1G07GV.msg' | ''  | ''      | ''     | 'Level-1' | 'NA'    | '2000V' | '200V' | '0 MILS'             | '0 MILS'            | '20191122'
 '74LVC1G07GV' | 'SMLF'    | 'IC'     | 'AL1G0007001SEL1'(!) = ''       | ''               | 'AL1G0007001SEL1' |'SC-74A_2-9X1-5'| 'IC OTHER(5P) 74LVC1G07GV(SOT753)SELASN' | 'NXP'   | '74LVC1G07GV' | 'EP(V1)'     | 'EP(V1)'  | 'S3D-ALAN' | 'IC'  | ''      | 'NXP_74LVC1G07GV.pdf' | ''            | 'SEL_15QPN.xlsx'  | ''  | ''      | ''     | 'Level-1' | 'NA'    | '2000V' | '200V' | '0 MILS'             | '0 MILS'            | '20230726'
 '74LVC1G07GV' | 'SMLF'    | 'EMPTY'  | 'AL1G0007001SEL1'(!) = ''       | ''               | 'AL1G0007001SEL1' |'SC-74A_2-9X1-5'| 'IC OTHER(5P) 74LVC1G07GV(SOT753)SELASN' | 'NXP'   | '74LVC1G07GV' | 'EP(V1)'     | 'EP(V1)'  | 'S3D-ALAN' | 'IC'  | ''      | 'NXP_74LVC1G07GV.pdf' | ''            | 'SEL_15QPN.xlsx'  | ''  | ''      | ''     | 'Level-1' | 'NA'    | '2000V' | '200V' | '0 MILS'             | '0 MILS'            | '20230726'

END_PART

END.

